(kicad_pcb
	(version 20260206)
	(generator "pcbnew")
	(generator_version "10.0")
	(general
		(thickness 1.6)
		(legacy_teardrops no)
	)
	(paper "A4")
	(title_block
		(title "04192023_DAF0TMB3IC0_F0TG_MB_C_brd_V02_OCP.brd")
		(comment 1 "Grand Teton / footprints 2314-2319 of 8354")
	)
	(layers
		(0 "F.Cu" signal "TOP")
		(4 "In1.Cu" signal "GND")
		(6 "In2.Cu" signal "IN1")
		(8 "In3.Cu" signal "GND1")
		(10 "In4.Cu" signal "IN2")
		(12 "In5.Cu" signal "GND2")
		(14 "In6.Cu" signal "IN3")
		(16 "In7.Cu" signal "GND3")
		(18 "In8.Cu" signal "VCC")
		(20 "In9.Cu" signal "VCC1")
		(22 "In10.Cu" signal "GND4")
		(24 "In11.Cu" signal "IN4")
		(26 "In12.Cu" signal "GND5")
		(28 "In13.Cu" signal "IN5")
		(30 "In14.Cu" signal "GND6")
		(32 "In15.Cu" signal "IN6")
		(34 "In16.Cu" signal "GND7")
		(2 "B.Cu" signal "BOTTOM")
		(9 "F.Adhes" user "F.Adhesive")
		(11 "B.Adhes" user "B.Adhesive")
		(13 "F.Paste" user "Package Geometry/Pastemask Top")
		(15 "B.Paste" user "Package Geometry/Pastemask Bottom")
		(5 "F.SilkS" user "Ref Des/Silkscreen Top")
		(7 "B.SilkS" user "Ref Des/Silkscreen Bottom")
		(1 "F.Mask" user "Board Geometry/Soldermask Top")
		(3 "B.Mask" user "Board Geometry/Soldermask Bottom")
		(17 "Dwgs.User" user "User.Drawings")
		(19 "Cmts.User" user "User.Comments")
		(21 "Eco1.User" user "User.Eco1")
		(23 "Eco2.User" user "User.Eco2")
		(25 "Edge.Cuts" user "Board Geometry/Outline")
		(27 "Margin" user)
		(31 "F.CrtYd" user "Package Geometry/Place Bound Top")
		(29 "B.CrtYd" user "Package Geometry/Place Bound Bottom")
		(35 "F.Fab" user "Ref Des/Assembly Top")
		(33 "B.Fab" user "Ref Des/Assembly Bottom")
	)
	(footprint ""
		(layer "F.Cu")
		(at 331.365098 -331.969364 180)
		(property "Reference" "PC189"
			(at 0 0 180)
			(layer "F.SilkS")
			(hide yes)
			(effects
				(font
					(size 1.27 1.27)
				)
			)
		)
		(property "Value" ""
			(at 0 0 180)
			(layer "F.Fab")
			(effects
				(font
					(size 1.27 1.27)
				)
			)
		)
		(duplicate_pad_numbers_are_jumpers no)
		(fp_line
			(start 0.7874 0.4064)
			(end -0.7874 0.4064)
			(stroke
				(width 0.1524)
				(type default)
			)
			(layer "F.SilkS")
		)
		(fp_line
			(start 0.7874 -0.4064)
			(end 0.7874 0.4064)
			(stroke
				(width 0.1524)
				(type default)
			)
			(layer "F.SilkS")
		)
		(fp_line
			(start -0.7874 0.4064)
			(end -0.7874 -0.4064)
			(stroke
				(width 0.1524)
				(type default)
			)
			(layer "F.SilkS")
		)
		(fp_line
			(start -0.7874 -0.4064)
			(end 0.7874 -0.4064)
			(stroke
				(width 0.1524)
				(type default)
			)
			(layer "F.SilkS")
		)
		(fp_line
			(start 0.67945 0.3048)
			(end 0.120396 0.3048)
			(stroke
				(width 0.1)
				(type default)
			)
			(layer "F.Fab")
		)
		(fp_line
			(start 0.67945 -0.3048)
			(end 0.67945 0.3048)
			(stroke
				(width 0.1)
				(type default)
			)
			(layer "F.Fab")
		)
		(fp_line
			(start 0.12065 -0.2794)
			(end 0.12065 -0.3048)
			(stroke
				(width 0.1)
				(type default)
			)
			(layer "F.Fab")
		)
		(fp_line
			(start 0.12065 -0.3048)
			(end 0.67945 -0.3048)
			(stroke
				(width 0.1)
				(type default)
			)
			(layer "F.Fab")
		)
		(fp_line
			(start 0.120396 0.3048)
			(end 0.120396 0.2794)
			(stroke
				(width 0.1)
				(type default)
			)
			(layer "F.Fab")
		)
		(fp_line
			(start 0.120396 0.2794)
			(end -0.12065 0.2794)
			(stroke
				(width 0.1)
				(type default)
			)
			(layer "F.Fab")
		)
		(fp_line
			(start -0.12065 0.3048)
			(end -0.67945 0.3048)
			(stroke
				(width 0.1)
				(type default)
			)
			(layer "F.Fab")
		)
		(fp_line
			(start -0.12065 0.2794)
			(end -0.12065 0.3048)
			(stroke
				(width 0.1)
				(type default)
			)
			(layer "F.Fab")
		)
		(fp_line
			(start -0.12065 -0.2794)
			(end 0.12065 -0.2794)
			(stroke
				(width 0.1)
				(type default)
			)
			(layer "F.Fab")
		)
		(fp_line
			(start -0.12065 -0.305054)
			(end -0.12065 -0.2794)
			(stroke
				(width 0.1)
				(type default)
			)
			(layer "F.Fab")
		)
		(fp_line
			(start -0.67945 0.3048)
			(end -0.67945 -0.305054)
			(stroke
				(width 0.1)
				(type default)
			)
			(layer "F.Fab")
		)
		(fp_line
			(start -0.67945 -0.305054)
			(end -0.12065 -0.305054)
			(stroke
				(width 0.1)
				(type default)
			)
			(layer "F.Fab")
		)
		(pad "1" smd circle
			(at -0.40005 0 180)
			(size 0 0)
			(layers "F.Cu" "F.Mask" "F.Paste")
			(net "SW_PVDDCR_CPU1_P0_SW1")
		)
		(pad "2" smd circle
			(at 0.40005 0 180)
			(size 0 0)
			(layers "F.Cu" "F.Mask" "F.Paste")
			(net "SW_PVDDCR_CPU1_P0_SW1_RC")
		)
	)
	(footprint ""
		(layer "F.Cu")
		(at 103.886 -426.466 -90)
		(property "Reference" "R3488"
			(at 0 0 270)
			(layer "F.SilkS")
			(hide yes)
			(effects
				(font
					(size 1.27 1.27)
				)
			)
		)
		(property "Value" ""
			(at 0 0 270)
			(layer "F.Fab")
			(effects
				(font
					(size 1.27 1.27)
				)
			)
		)
		(duplicate_pad_numbers_are_jumpers no)
		(fp_line
			(start -0.7874 0.4064)
			(end -0.7874 -0.4064)
			(stroke
				(width 0.1524)
				(type default)
			)
			(layer "F.SilkS")
		)
		(fp_line
			(start 0.7874 0.4064)
			(end -0.7874 0.4064)
			(stroke
				(width 0.1524)
				(type default)
			)
			(layer "F.SilkS")
		)
		(fp_line
			(start -0.7874 -0.4064)
			(end 0.7874 -0.4064)
			(stroke
				(width 0.1524)
				(type default)
			)
			(layer "F.SilkS")
		)
		(fp_line
			(start 0.7874 -0.4064)
			(end 0.7874 0.4064)
			(stroke
				(width 0.1524)
				(type default)
			)
			(layer "F.SilkS")
		)
		(fp_line
			(start -0.67945 0.3048)
			(end -0.67945 -0.305054)
			(stroke
				(width 0.1)
				(type default)
			)
			(layer "F.Fab")
		)
		(fp_line
			(start -0.12065 0.3048)
			(end -0.67945 0.3048)
			(stroke
				(width 0.1)
				(type default)
			)
			(layer "F.Fab")
		)
		(fp_line
			(start 0.120396 0.3048)
			(end 0.120396 0.2794)
			(stroke
				(width 0.1)
				(type default)
			)
			(layer "F.Fab")
		)
		(fp_line
			(start 0.67945 0.3048)
			(end 0.120396 0.3048)
			(stroke
				(width 0.1)
				(type default)
			)
			(layer "F.Fab")
		)
		(fp_line
			(start -0.12065 0.2794)
			(end -0.12065 0.3048)
			(stroke
				(width 0.1)
				(type default)
			)
			(layer "F.Fab")
		)
		(fp_line
			(start 0.120396 0.2794)
			(end -0.12065 0.2794)
			(stroke
				(width 0.1)
				(type default)
			)
			(layer "F.Fab")
		)
		(fp_line
			(start -0.12065 -0.2794)
			(end 0.12065 -0.2794)
			(stroke
				(width 0.1)
				(type default)
			)
			(layer "F.Fab")
		)
		(fp_line
			(start 0.12065 -0.2794)
			(end 0.12065 -0.3048)
			(stroke
				(width 0.1)
				(type default)
			)
			(layer "F.Fab")
		)
		(fp_line
			(start 0.12065 -0.3048)
			(end 0.67945 -0.3048)
			(stroke
				(width 0.1)
				(type default)
			)
			(layer "F.Fab")
		)
		(fp_line
			(start 0.67945 -0.3048)
			(end 0.67945 0.3048)
			(stroke
				(width 0.1)
				(type default)
			)
			(layer "F.Fab")
		)
		(fp_line
			(start -0.67945 -0.305054)
			(end -0.12065 -0.305054)
			(stroke
				(width 0.1)
				(type default)
			)
			(layer "F.Fab")
		)
		(fp_line
			(start -0.12065 -0.305054)
			(end -0.12065 -0.2794)
			(stroke
				(width 0.1)
				(type default)
			)
			(layer "F.Fab")
		)
		(pad "1" smd circle
			(at -0.40005 0 270)
			(size 0 0)
			(layers "F.Cu" "F.Mask" "F.Paste")
			(net "P3V3_AUX")
		)
		(pad "2" smd circle
			(at 0.40005 0 270)
			(size 0 0)
			(layers "F.Cu" "F.Mask" "F.Paste")
			(net "GPU_FPGA_EROT_RST_N")
		)
	)
	(footprint ""
		(layer "F.Cu")
		(at 303.200308 -45.005498 180)
		(property "Reference" "C2051"
			(at 0 0 180)
			(layer "F.SilkS")
			(hide yes)
			(effects
				(font
					(size 1.27 1.27)
				)
			)
		)
		(property "Value" ""
			(at 0 0 180)
			(layer "F.Fab")
			(effects
				(font
					(size 1.27 1.27)
				)
			)
		)
		(duplicate_pad_numbers_are_jumpers no)
		(fp_line
			(start 0.7874 0.4064)
			(end -0.7874 0.4064)
			(stroke
				(width 0.1524)
				(type default)
			)
			(layer "F.SilkS")
		)
		(fp_line
			(start 0.7874 -0.4064)
			(end 0.7874 0.4064)
			(stroke
				(width 0.1524)
				(type default)
			)
			(layer "F.SilkS")
		)
		(fp_line
			(start -0.7874 0.4064)
			(end -0.7874 -0.4064)
			(stroke
				(width 0.1524)
				(type default)
			)
			(layer "F.SilkS")
		)
		(fp_line
			(start -0.7874 -0.4064)
			(end 0.7874 -0.4064)
			(stroke
				(width 0.1524)
				(type default)
			)
			(layer "F.SilkS")
		)
		(fp_line
			(start 0.67945 0.3048)
			(end 0.120396 0.3048)
			(stroke
				(width 0.1)
				(type default)
			)
			(layer "F.Fab")
		)
		(fp_line
			(start 0.67945 -0.3048)
			(end 0.67945 0.3048)
			(stroke
				(width 0.1)
				(type default)
			)
			(layer "F.Fab")
		)
		(fp_line
			(start 0.12065 -0.2794)
			(end 0.12065 -0.3048)
			(stroke
				(width 0.1)
				(type default)
			)
			(layer "F.Fab")
		)
		(fp_line
			(start 0.12065 -0.3048)
			(end 0.67945 -0.3048)
			(stroke
				(width 0.1)
				(type default)
			)
			(layer "F.Fab")
		)
		(fp_line
			(start 0.120396 0.3048)
			(end 0.120396 0.2794)
			(stroke
				(width 0.1)
				(type default)
			)
			(layer "F.Fab")
		)
		(fp_line
			(start 0.120396 0.2794)
			(end -0.12065 0.2794)
			(stroke
				(width 0.1)
				(type default)
			)
			(layer "F.Fab")
		)
		(fp_line
			(start -0.12065 0.3048)
			(end -0.67945 0.3048)
			(stroke
				(width 0.1)
				(type default)
			)
			(layer "F.Fab")
		)
		(fp_line
			(start -0.12065 0.2794)
			(end -0.12065 0.3048)
			(stroke
				(width 0.1)
				(type default)
			)
			(layer "F.Fab")
		)
		(fp_line
			(start -0.12065 -0.2794)
			(end 0.12065 -0.2794)
			(stroke
				(width 0.1)
				(type default)
			)
			(layer "F.Fab")
		)
		(fp_line
			(start -0.12065 -0.305054)
			(end -0.12065 -0.2794)
			(stroke
				(width 0.1)
				(type default)
			)
			(layer "F.Fab")
		)
		(fp_line
			(start -0.67945 0.3048)
			(end -0.67945 -0.305054)
			(stroke
				(width 0.1)
				(type default)
			)
			(layer "F.Fab")
		)
		(fp_line
			(start -0.67945 -0.305054)
			(end -0.12065 -0.305054)
			(stroke
				(width 0.1)
				(type default)
			)
			(layer "F.Fab")
		)
		(pad "1" smd circle
			(at -0.40005 0 180)
			(size 0 0)
			(layers "F.Cu" "F.Mask" "F.Paste")
			(net "P3V3_ADC128_VCC")
		)
		(pad "2" smd circle
			(at 0.40005 0 180)
			(size 0 0)
			(layers "F.Cu" "F.Mask" "F.Paste")
			(net "GND")
		)
	)
	(footprint ""
		(layer "F.Cu")
		(at 37.853112 -368.455448 90)
		(property "Reference" "PR253"
			(at 0 0 90)
			(layer "F.SilkS")
			(hide yes)
			(effects
				(font
					(size 1.27 1.27)
				)
			)
		)
		(property "Value" ""
			(at 0 0 90)
			(layer "F.Fab")
			(effects
				(font
					(size 1.27 1.27)
				)
			)
		)
		(duplicate_pad_numbers_are_jumpers no)
		(fp_line
			(start 0.7874 -0.4064)
			(end 0.7874 0.4064)
			(stroke
				(width 0.1524)
				(type default)
			)
			(layer "F.SilkS")
		)
		(fp_line
			(start -0.7874 -0.4064)
			(end 0.7874 -0.4064)
			(stroke
				(width 0.1524)
				(type default)
			)
			(layer "F.SilkS")
		)
		(fp_line
			(start 0.7874 0.4064)
			(end -0.7874 0.4064)
			(stroke
				(width 0.1524)
				(type default)
			)
			(layer "F.SilkS")
		)
		(fp_line
			(start -0.7874 0.4064)
			(end -0.7874 -0.4064)
			(stroke
				(width 0.1524)
				(type default)
			)
			(layer "F.SilkS")
		)
		(fp_line
			(start -0.12065 -0.305054)
			(end -0.12065 -0.2794)
			(stroke
				(width 0.1)
				(type default)
			)
			(layer "F.Fab")
		)
		(fp_line
			(start -0.67945 -0.305054)
			(end -0.12065 -0.305054)
			(stroke
				(width 0.1)
				(type default)
			)
			(layer "F.Fab")
		)
		(fp_line
			(start 0.67945 -0.3048)
			(end 0.67945 0.3048)
			(stroke
				(width 0.1)
				(type default)
			)
			(layer "F.Fab")
		)
		(fp_line
			(start 0.12065 -0.3048)
			(end 0.67945 -0.3048)
			(stroke
				(width 0.1)
				(type default)
			)
			(layer "F.Fab")
		)
		(fp_line
			(start 0.12065 -0.2794)
			(end 0.12065 -0.3048)
			(stroke
				(width 0.1)
				(type default)
			)
			(layer "F.Fab")
		)
		(fp_line
			(start -0.12065 -0.2794)
			(end 0.12065 -0.2794)
			(stroke
				(width 0.1)
				(type default)
			)
			(layer "F.Fab")
		)
		(fp_line
			(start 0.120396 0.2794)
			(end -0.12065 0.2794)
			(stroke
				(width 0.1)
				(type default)
			)
			(layer "F.Fab")
		)
		(fp_line
			(start -0.12065 0.2794)
			(end -0.12065 0.3048)
			(stroke
				(width 0.1)
				(type default)
			)
			(layer "F.Fab")
		)
		(fp_line
			(start 0.67945 0.3048)
			(end 0.120396 0.3048)
			(stroke
				(width 0.1)
				(type default)
			)
			(layer "F.Fab")
		)
		(fp_line
			(start 0.120396 0.3048)
			(end 0.120396 0.2794)
			(stroke
				(width 0.1)
				(type default)
			)
			(layer "F.Fab")
		)
		(fp_line
			(start -0.12065 0.3048)
			(end -0.67945 0.3048)
			(stroke
				(width 0.1)
				(type default)
			)
			(layer "F.Fab")
		)
		(fp_line
			(start -0.67945 0.3048)
			(end -0.67945 -0.305054)
			(stroke
				(width 0.1)
				(type default)
			)
			(layer "F.Fab")
		)
		(pad "1" smd circle
			(at -0.40005 0 90)
			(size 0 0)
			(layers "F.Cu" "F.Mask" "F.Paste")
			(net "PVDDCR_CPU1_P1_VCC")
		)
		(pad "2" smd circle
			(at 0.40005 0 90)
			(size 0 0)
			(layers "F.Cu" "F.Mask" "F.Paste")
			(net "P3V3_AUX")
		)
	)
	(footprint ""
		(layer "F.Cu")
		(at 303.868328 -404.392892)
		(property "Reference" "C564"
			(at 0 0 0)
			(layer "F.SilkS")
			(hide yes)
			(effects
				(font
					(size 1.27 1.27)
				)
			)
		)
		(property "Value" ""
			(at 0 0 0)
			(layer "F.Fab")
			(effects
				(font
					(size 1.27 1.27)
				)
			)
		)
		(duplicate_pad_numbers_are_jumpers no)
		(fp_line
			(start -1.524 -0.762)
			(end 1.524 -0.762)
			(stroke
				(width 0.1524)
				(type default)
			)
			(layer "F.SilkS")
		)
		(fp_line
			(start -1.524 0.762)
			(end -1.524 -0.762)
			(stroke
				(width 0.1524)
				(type default)
			)
			(layer "F.SilkS")
		)
		(fp_line
			(start 1.524 -0.762)
			(end 1.524 0.762)
			(stroke
				(width 0.1524)
				(type default)
			)
			(layer "F.SilkS")
		)
		(fp_line
			(start 1.524 0.762)
			(end -1.524 0.762)
			(stroke
				(width 0.1524)
				(type default)
			)
			(layer "F.SilkS")
		)
		(fp_line
			(start -1.1049 -0.724916)
			(end -1.1049 0.724916)
			(stroke
				(width 0.1)
				(type default)
			)
			(layer "F.Fab")
		)
		(fp_line
			(start -1.1049 0.724916)
			(end 1.1049 0.724916)
			(stroke
				(width 0.1)
				(type default)
			)
			(layer "F.Fab")
		)
		(fp_line
			(start 1.1049 -0.724916)
			(end -1.1049 -0.724916)
			(stroke
				(width 0.1)
				(type default)
			)
			(layer "F.Fab")
		)
		(fp_line
			(start 1.1049 0.724916)
			(end 1.1049 -0.724916)
			(stroke
				(width 0.1)
				(type default)
			)
			(layer "F.Fab")
		)
		(pad "1" smd rect
			(at -0.889 0 180)
			(size 1.016 1.27)
			(layers "F.Cu" "F.Mask" "F.Paste")
			(net "P0V9_CPU0_RT0_2A")
		)
		(pad "2" smd rect
			(at 0.889 0 180)
			(size 1.016 1.27)
			(layers "F.Cu" "F.Mask" "F.Paste")
			(net "GND")
		)
	)
	(footprint ""
		(layer "F.Cu")
		(at 194.2211 -404.300182)
		(property "Reference" "PR3916"
			(at 0 0 0)
			(layer "F.SilkS")
			(hide yes)
			(effects
				(font
					(size 1.27 1.27)
				)
			)
		)
		(property "Value" ""
			(at 0 0 0)
			(layer "F.Fab")
			(effects
				(font
					(size 1.27 1.27)
				)
			)
		)
		(duplicate_pad_numbers_are_jumpers no)
		(fp_line
			(start -0.7874 -0.4064)
			(end 0.7874 -0.4064)
			(stroke
				(width 0.1524)
				(type default)
			)
			(layer "F.SilkS")
		)
		(fp_line
			(start -0.7874 0.4064)
			(end -0.7874 -0.4064)
			(stroke
				(width 0.1524)
				(type default)
			)
			(layer "F.SilkS")
		)
		(fp_line
			(start 0.7874 -0.4064)
			(end 0.7874 0.4064)
			(stroke
				(width 0.1524)
				(type default)
			)
			(layer "F.SilkS")
		)
		(fp_line
			(start 0.7874 0.4064)
			(end -0.7874 0.4064)
			(stroke
				(width 0.1524)
				(type default)
			)
			(layer "F.SilkS")
		)
		(fp_line
			(start -0.67945 -0.305054)
			(end -0.12065 -0.305054)
			(stroke
				(width 0.1)
				(type default)
			)
			(layer "F.Fab")
		)
		(fp_line
			(start -0.67945 0.3048)
			(end -0.67945 -0.305054)
			(stroke
				(width 0.1)
				(type default)
			)
			(layer "F.Fab")
		)
		(fp_line
			(start -0.12065 -0.305054)
			(end -0.12065 -0.2794)
			(stroke
				(width 0.1)
				(type default)
			)
			(layer "F.Fab")
		)
		(fp_line
			(start -0.12065 -0.2794)
			(end 0.12065 -0.2794)
			(stroke
				(width 0.1)
				(type default)
			)
			(layer "F.Fab")
		)
		(fp_line
			(start -0.12065 0.2794)
			(end -0.12065 0.3048)
			(stroke
				(width 0.1)
				(type default)
			)
			(layer "F.Fab")
		)
		(fp_line
			(start -0.12065 0.3048)
			(end -0.67945 0.3048)
			(stroke
				(width 0.1)
				(type default)
			)
			(layer "F.Fab")
		)
		(fp_line
			(start 0.120396 0.2794)
			(end -0.12065 0.2794)
			(stroke
				(width 0.1)
				(type default)
			)
			(layer "F.Fab")
		)
		(fp_line
			(start 0.120396 0.3048)
			(end 0.120396 0.2794)
			(stroke
				(width 0.1)
				(type default)
			)
			(layer "F.Fab")
		)
		(fp_line
			(start 0.12065 -0.3048)
			(end 0.67945 -0.3048)
			(stroke
				(width 0.1)
				(type default)
			)
			(layer "F.Fab")
		)
		(fp_line
			(start 0.12065 -0.2794)
			(end 0.12065 -0.3048)
			(stroke
				(width 0.1)
				(type default)
			)
			(layer "F.Fab")
		)
		(fp_line
			(start 0.67945 -0.3048)
			(end 0.67945 0.3048)
			(stroke
				(width 0.1)
				(type default)
			)
			(layer "F.Fab")
		)
		(fp_line
			(start 0.67945 0.3048)
			(end 0.120396 0.3048)
			(stroke
				(width 0.1)
				(type default)
			)
			(layer "F.Fab")
		)
		(pad "1" smd circle
			(at -0.40005 0)
			(size 0 0)
			(layers "F.Cu" "F.Mask" "F.Paste")
			(net "HSC_SCREF")
		)
		(pad "2" smd circle
			(at 0.40005 0)
			(size 0 0)
			(layers "F.Cu" "F.Mask" "F.Paste")
			(net "HSC_SCREF_1")
		)
	)
)
